# S9S_MB_2U (Grand Teton) — schematic netlist excerpt (pin names and nets, part order shuffled) for the footprints in the layout excerpt that follows; sources: Cadence DE-HDL packaged netlist, KiCad conversion of 03242023_DA0F0TMBIJ0_F0T_Motherboard_J_brd_V01_OCP.brd

R425  Q_RES  200 1% CHIP  pkg 0402LF  page 153 : A = SMB_OCP_SFF_3V3AUX_BUF_R_SDA ; B = SMB_OCP_SFF_3V3AUX_BUF_SDA
C1127  Q_CAP  0.01UF 50V 10% X7R  pkg C0402  page 217 : A = P3V3_AUX_FPGA_VCCIO2 ; B = GND

(kicad_pcb
	(version 20260206)
	(generator "pcbnew")
	(generator_version "10.0")
	(general
		(thickness 1.6)
		(legacy_teardrops no)
	)
	(paper "A4")
	(title_block
		(title "03242023_DA0F0TMBIJ0_F0T_Motherboard_J_brd_V01_OCP.brd")
		(comment 1 "Grand Teton / footprints 4635-4636 of 6105")
	)
	(layers
		(0 "F.Cu" signal "TOP")
		(4 "In1.Cu" signal "GND")
		(6 "In2.Cu" signal "IN1")
		(8 "In3.Cu" signal "GND1")
		(10 "In4.Cu" signal "IN2")
		(12 "In5.Cu" signal "GND2")
		(14 "In6.Cu" signal "IN3")
		(16 "In7.Cu" signal "GND3")
		(18 "In8.Cu" signal "VCC")
		(20 "In9.Cu" signal "VCC1")
		(22 "In10.Cu" signal "GND4")
		(24 "In11.Cu" signal "IN4")
		(26 "In12.Cu" signal "GND5")
		(28 "In13.Cu" signal "IN5")
		(30 "In14.Cu" signal "GND6")
		(32 "In15.Cu" signal "IN6")
		(34 "In16.Cu" signal "GND7")
		(2 "B.Cu" signal "BOTTOM")
		(9 "F.Adhes" user "F.Adhesive")
		(11 "B.Adhes" user "B.Adhesive")
		(13 "F.Paste" user "Package Geometry/Pastemask Top")
		(15 "B.Paste" user "Package Geometry/Pastemask Bottom")
		(5 "F.SilkS" user "Ref Des/Silkscreen Top")
		(7 "B.SilkS" user "Ref Des/Silkscreen Bottom")
		(1 "F.Mask" user "Board Geometry/Soldermask Top")
		(3 "B.Mask" user "Board Geometry/Soldermask Bottom")
		(17 "Dwgs.User" user "User.Drawings")
		(19 "Cmts.User" user "User.Comments")
		(21 "Eco1.User" user "User.Eco1")
		(23 "Eco2.User" user "User.Eco2")
		(25 "Edge.Cuts" user "Board Geometry/Outline")
		(27 "Margin" user)
		(31 "F.CrtYd" user "Package Geometry/Place Bound Top")
		(29 "B.CrtYd" user "Package Geometry/Place Bound Bottom")
		(35 "F.Fab" user "Ref Des/Assembly Top")
		(33 "B.Fab" user "Ref Des/Assembly Bottom")
	)
	(footprint ""
		(layer "B.Cu")
		(at 181.755542 -114.575336)
		(property "Reference" "C1127"
			(at 0 0 0)
			(layer "B.SilkS")
			(hide yes)
			(effects
				(font
					(size 1.27 1.27)
				)
				(justify mirror)
			)
		)
		(property "Value" ""
			(at 0 0 0)
			(layer "B.Fab")
			(effects
				(font
					(size 1.27 1.27)
				)
				(justify mirror)
			)
		)
		(duplicate_pad_numbers_are_jumpers no)
		(fp_line
			(start -0.69215 -0.2921)
			(end -0.69215 0.2921)
			(stroke
				(width 0.1524)
				(type default)
			)
			(layer "B.SilkS")
		)
		(fp_line
			(start -0.69215 0.2921)
			(end 0.69215 0.2921)
			(stroke
				(width 0.1524)
				(type default)
			)
			(layer "B.SilkS")
		)
		(fp_line
			(start 0.69215 -0.2921)
			(end -0.69215 -0.2921)
			(stroke
				(width 0.1524)
				(type default)
			)
			(layer "B.SilkS")
		)
		(fp_line
			(start 0.69215 0.2921)
			(end 0.69215 -0.2921)
			(stroke
				(width 0.1524)
				(type default)
			)
			(layer "B.SilkS")
		)
		(fp_line
			(start -0.51435 -0.2794)
			(end -0.51435 0.2794)
			(stroke
				(width 0.1)
				(type default)
			)
			(layer "B.Fab")
		)
		(fp_line
			(start -0.51435 0.2794)
			(end 0.51435 0.2794)
			(stroke
				(width 0.1)
				(type default)
			)
			(layer "B.Fab")
		)
		(fp_line
			(start 0.51435 -0.2794)
			(end -0.51435 -0.2794)
			(stroke
				(width 0.1)
				(type default)
			)
			(layer "B.Fab")
		)
		(fp_line
			(start 0.51435 0.2794)
			(end 0.51435 -0.2794)
			(stroke
				(width 0.1)
				(type default)
			)
			(layer "B.Fab")
		)
		(pad "1" smd circle
			(at 0.40005 0 180)
			(size 0 0)
			(layers "B.Cu" "B.Mask" "B.Paste")
			(net "P3V3_AUX_FPGA_VCCIO2")
		)
		(pad "2" smd circle
			(at -0.40005 0 180)
			(size 0 0)
			(layers "B.Cu" "B.Mask" "B.Paste")
			(net "GND")
		)
		(zone
			(layer "B.Cu")
			(hatch none 0.5)
			(connect_pads
				(clearance 0)
			)
			(min_thickness 0.25)
			(keepout
				(tracks not_allowed)
				(vias allowed)
				(pads allowed)
				(copperpour not_allowed)
				(footprints allowed)
			)
			(placement
				(enabled no)
				(sheetname "")
			)
			(fill
				(thermal_gap 0.5)
				(thermal_bridge_width 0.5)
				(island_removal_mode 0)
			)
			(polygon
				(pts
					(xy 181.946042 -114.487706) (xy 181.854602 -114.42954) (xy 181.655212 -114.42954) (xy 181.565042 -114.487706)
					(xy 181.565042 -114.662966) (xy 181.655212 -114.721386) (xy 181.854602 -114.721386) (xy 181.946042 -114.66322)
				)
			)
		)
	)
	(footprint ""
		(layer "B.Cu")
		(at 450.43725 -44.171362)
		(property "Reference" "R425"
			(at 0 0 0)
			(layer "B.SilkS")
			(hide yes)
			(effects
				(font
					(size 1.27 1.27)
				)
				(justify mirror)
			)
		)
		(property "Value" ""
			(at 0 0 0)
			(layer "B.Fab")
			(effects
				(font
					(size 1.27 1.27)
				)
				(justify mirror)
			)
		)
		(duplicate_pad_numbers_are_jumpers no)
		(fp_line
			(start -0.7874 -0.4064)
			(end -0.7874 0.4064)
			(stroke
				(width 0.1524)
				(type default)
			)
			(layer "B.SilkS")
		)
		(fp_line
			(start -0.7874 0.4064)
			(end 0.7874 0.4064)
			(stroke
				(width 0.1524)
				(type default)
			)
			(layer "B.SilkS")
		)
		(fp_line
			(start 0.7874 -0.4064)
			(end -0.7874 -0.4064)
			(stroke
				(width 0.1524)
				(type default)
			)
			(layer "B.SilkS")
		)
		(fp_line
			(start 0.7874 0.4064)
			(end 0.7874 -0.4064)
			(stroke
				(width 0.1524)
				(type default)
			)
			(layer "B.SilkS")
		)
		(fp_line
			(start -0.67945 -0.3048)
			(end -0.67945 0.3048)
			(stroke
				(width 0.1)
				(type default)
			)
			(layer "B.Fab")
		)
		(fp_line
			(start -0.67945 0.3048)
			(end -0.120396 0.3048)
			(stroke
				(width 0.1)
				(type default)
			)
			(layer "B.Fab")
		)
		(fp_line
			(start -0.12065 -0.3048)
			(end -0.67945 -0.3048)
			(stroke
				(width 0.1)
				(type default)
			)
			(layer "B.Fab")
		)
		(fp_line
			(start -0.12065 -0.2794)
			(end -0.12065 -0.3048)
			(stroke
				(width 0.1)
				(type default)
			)
			(layer "B.Fab")
		)
		(fp_line
			(start -0.120396 0.2794)
			(end 0.12065 0.2794)
			(stroke
				(width 0.1)
				(type default)
			)
			(layer "B.Fab")
		)
		(fp_line
			(start -0.120396 0.3048)
			(end -0.120396 0.2794)
			(stroke
				(width 0.1)
				(type default)
			)
			(layer "B.Fab")
		)
		(fp_line
			(start 0.12065 -0.305054)
			(end 0.12065 -0.2794)
			(stroke
				(width 0.1)
				(type default)
			)
			(layer "B.Fab")
		)
		(fp_line
			(start 0.12065 -0.2794)
			(end -0.12065 -0.2794)
			(stroke
				(width 0.1)
				(type default)
			)
			(layer "B.Fab")
		)
		(fp_line
			(start 0.12065 0.2794)
			(end 0.12065 0.3048)
			(stroke
				(width 0.1)
				(type default)
			)
			(layer "B.Fab")
		)
		(fp_line
			(start 0.12065 0.3048)
			(end 0.67945 0.3048)
			(stroke
				(width 0.1)
				(type default)
			)
			(layer "B.Fab")
		)
		(fp_line
			(start 0.67945 -0.305054)
			(end 0.12065 -0.305054)
			(stroke
				(width 0.1)
				(type default)
			)
			(layer "B.Fab")
		)
		(fp_line
			(start 0.67945 0.3048)
			(end 0.67945 -0.305054)
			(stroke
				(width 0.1)
				(type default)
			)
			(layer "B.Fab")
		)
		(pad "1" smd circle
			(at 0.40005 0 180)
			(size 0 0)
			(layers "B.Cu" "B.Mask" "B.Paste")
			(net "SMB_OCP_SFF_3V3AUX_BUF_R_SDA")
		)
		(pad "2" smd circle
			(at -0.40005 0 180)
			(size 0 0)
			(layers "B.Cu" "B.Mask" "B.Paste")
			(net "SMB_OCP_SFF_3V3AUX_BUF_SDA")
		)
	)
)
